(kicad_pcb
	(version 20241229)
	(generator "pcbnew")
	(generator_version "9.0")
	(general
		(thickness 1.62)
		(legacy_teardrops no)
	)
	(paper "A4")
	(title_block
		(title "OCuLink to 10GbE adapter")
		(date "2026-02-23")
		(rev "1.1.0")
		(company "Antmicro Ltd")
		(comment 1 "www.antmicro.com")
		(comment 9 "footprints 510-510 of 510")
	)
	(layers
		(0 "F.Cu" signal)
		(4 "In1.Cu" signal)
		(6 "In2.Cu" signal)
		(8 "In3.Cu" signal)
		(10 "In4.Cu" signal)
		(12 "In5.Cu" signal)
		(14 "In6.Cu" signal)
		(2 "B.Cu" signal)
		(9 "F.Adhes" user "F.Adhesive")
		(11 "B.Adhes" user "B.Adhesive")
		(13 "F.Paste" user)
		(15 "B.Paste" user)
		(5 "F.SilkS" user "F.Silkscreen")
		(7 "B.SilkS" user "B.Silkscreen")
		(1 "F.Mask" user)
		(3 "B.Mask" user)
		(17 "Dwgs.User" user "User.Drawings")
		(19 "Cmts.User" user "User.Comments")
		(21 "Eco1.User" user "User.Eco1")
		(23 "Eco2.User" user "User.Eco2")
		(25 "Edge.Cuts" user)
		(27 "Margin" user)
		(31 "F.CrtYd" user "F.Courtyard")
		(29 "B.CrtYd" user "B.Courtyard")
		(35 "F.Fab" user)
		(33 "B.Fab" user)
	)
	(footprint "antmicro-footprints:C_0402_1005Metric"
		(layer "B.Cu")
		(at 80.22 103.23 90)
		(descr "Capacitor SMD 0402")
		(tags "capacitor SMD 0402")
		(property "Reference" "C183"
			(at -11.62 -0.04 90)
			(layer "B.SilkS")
			(effects
				(font
					(size 0.7 0.7)
					(thickness 0.15)
				)
				(justify right top mirror)
			)
		)
		(property "Value" "C_1u_25V_0402"
			(at -1.022927 -2.155213 90)
			(layer "B.Fab")
			(hide yes)
			(effects
				(font
					(size 0.7 0.7)
					(thickness 0.15)
				)
				(justify right top mirror)
			)
		)
		(property "Datasheet" "https://www.murata.com/products/productdetail?partno=GRM155R61E105KE11%23"
			(at 0 0 90)
			(layer "B.Fab")
			(hide yes)
			(effects
				(font
					(size 1.27 1.27)
					(thickness 0.15)
				)
				(justify mirror)
			)
		)
		(property "Description" "SMD Multilayer Ceramic Capacitor, 1 µF, 25 V, 0402 [1005 Metric], ± 10%, X5R, GRM Series"
			(at 0 0 90)
			(layer "B.Fab")
			(hide yes)
			(effects
				(font
					(size 1.27 1.27)
					(thickness 0.15)
				)
				(justify mirror)
			)
		)
		(property "MPN" "GRM155R61E105KE11J"
			(at 0 0 90)
			(unlocked yes)
			(layer "B.Fab")
			(hide yes)
			(effects
				(font
					(size 1 1)
					(thickness 0.15)
				)
				(justify mirror)
			)
		)
		(property "Manufacturer" "Murata"
			(at 0 0 90)
			(unlocked yes)
			(layer "B.Fab")
			(hide yes)
			(effects
				(font
					(size 1 1)
					(thickness 0.15)
				)
				(justify mirror)
			)
		)
		(property "License" "Apache-2.0"
			(at 0 0 90)
			(unlocked yes)
			(layer "B.Fab")
			(hide yes)
			(effects
				(font
					(size 1 1)
					(thickness 0.15)
				)
				(justify mirror)
			)
		)
		(property "Author" "Antmicro"
			(at 0 0 90)
			(unlocked yes)
			(layer "B.Fab")
			(hide yes)
			(effects
				(font
					(size 1 1)
					(thickness 0.15)
				)
				(justify mirror)
			)
		)
		(property "Val" "1u"
			(at 0 0 90)
			(unlocked yes)
			(layer "B.Fab")
			(hide yes)
			(effects
				(font
					(size 1 1)
					(thickness 0.15)
				)
				(justify mirror)
			)
		)
		(property "Voltage" "25V"
			(at 0 0 90)
			(unlocked yes)
			(layer "B.Fab")
			(hide yes)
			(effects
				(font
					(size 1 1)
					(thickness 0.15)
				)
				(justify mirror)
			)
		)
		(property "Dielectric" "X5R"
			(at 0 0 90)
			(unlocked yes)
			(layer "B.Fab")
			(hide yes)
			(effects
				(font
					(size 1 1)
					(thickness 0.15)
				)
				(justify mirror)
			)
		)
		(sheetname "/X710-AT2 power/")
		(sheetfile "x710-at2-power.kicad_sch")
		(attr smd)
		(fp_rect
			(start -0.925 0.47)
			(end 0.925 -0.47)
			(stroke
				(width 0.05)
				(type default)
			)
			(fill no)
			(layer "B.CrtYd")
		)
		(fp_line
			(start 0.504 -0.248)
			(end -0.494 -0.248)
			(stroke
				(width 0.15)
				(type solid)
			)
			(layer "B.Fab")
		)
		(fp_line
			(start -0.494 -0.248)
			(end -0.494 0.25)
			(stroke
				(width 0.15)
				(type solid)
			)
			(layer "B.Fab")
		)
		(fp_line
			(start 0.504 0.25)
			(end 0.504 -0.248)
			(stroke
				(width 0.15)
				(type solid)
			)
			(layer "B.Fab")
		)
		(fp_line
			(start -0.494 0.25)
			(end 0.504 0.25)
			(stroke
				(width 0.15)
				(type solid)
			)
			(layer "B.Fab")
		)
		(pad "1" smd roundrect
			(at -0.48 0 90)
			(size 0.59 0.64)
			(layers "B.Cu" "B.Mask" "B.Paste")
			(roundrect_rratio 0.25)
			(net 28 "GND")
			(pintype "passive")
		)
		(pad "2" smd roundrect
			(at 0.48 0 90)
			(size 0.59 0.64)
			(layers "B.Cu" "B.Mask" "B.Paste")
			(roundrect_rratio 0.25)
			(net 12 "XFI_VDD")
			(pintype "passive")
		)
	)
)
